# BASEBOARD_FAB2 (Tioga Pass) — schematic netlist excerpt (pin names and nets, part order shuffled) for the footprints in the layout excerpt that follows; sources: Cadence DE-HDL packaged netlist, KiCad conversion of Wiwynn_Tioga_Pass_MB.brd

R1L7  RES  4.75K 1% CHIP  pkg 0402  page 157 : A = P3V3_STBY ; B = FM_BMC_CPLD_MP_RST_N
C5D54  CAP_A  22.0UF 4V 20% X6S  pkg 0603V  page 217 : A = PVDDQ_ABC ; B = GND
R7A9  RES  2.26K 1.0% CHIP  pkg 0402  page 218 : A = P3V3_STBY ; B = PWRGD_PVDDQ_DEF

(kicad_pcb
	(version 20260206)
	(generator "pcbnew")
	(generator_version "10.0")
	(general
		(thickness 1.6)
		(legacy_teardrops no)
	)
	(paper "A4")
	(title_block
		(title "Wiwynn_Tioga_Pass_MB.brd")
		(comment 1 "Tioga Pass / footprints 722-724 of 4770")
	)
	(layers
		(0 "F.Cu" signal "TOP")
		(4 "In1.Cu" signal "L2GND")
		(6 "In2.Cu" signal "L3")
		(8 "In3.Cu" signal "L4GND")
		(10 "In4.Cu" signal "L5")
		(12 "In5.Cu" signal "L6GND")
		(14 "In6.Cu" signal "L7VCC")
		(16 "In7.Cu" signal "L8VCC")
		(18 "In8.Cu" signal "L9GND")
		(20 "In9.Cu" signal "L10")
		(22 "In10.Cu" signal "L11GND")
		(24 "In11.Cu" signal "L12")
		(26 "In12.Cu" signal "L13GND")
		(2 "B.Cu" signal "BOTTOM")
		(9 "F.Adhes" user "F.Adhesive")
		(11 "B.Adhes" user "B.Adhesive")
		(13 "F.Paste" user "Package Geometry/Pastemask Top")
		(15 "B.Paste" user "Package Geometry/Pastemask Bottom")
		(5 "F.SilkS" user "Ref Des/Silkscreen Top")
		(7 "B.SilkS" user "Ref Des/Silkscreen Bottom")
		(1 "F.Mask" user "Board Geometry/Soldermask Top")
		(3 "B.Mask" user "Board Geometry/Soldermask Bottom")
		(17 "Dwgs.User" user "User.Drawings")
		(19 "Cmts.User" user "User.Comments")
		(21 "Eco1.User" user "User.Eco1")
		(23 "Eco2.User" user "User.Eco2")
		(25 "Edge.Cuts" user "Board Geometry/Outline")
		(27 "Margin" user)
		(31 "F.CrtYd" user "Package Geometry/Place Bound Top")
		(29 "B.CrtYd" user "Package Geometry/Place Bound Bottom")
		(35 "F.Fab" user "Ref Des/Assembly Top")
		(33 "B.Fab" user "Ref Des/Assembly Bottom")
	)
	(footprint ""
		(layer "F.Cu")
		(at 264.453624 -69.885814 -90)
		(property "Reference" "C5D54"
			(at 0 0 270)
			(layer "F.SilkS")
			(hide yes)
			(effects
				(font
					(size 1.27 1.27)
				)
			)
		)
		(property "Value" ""
			(at 0 0 270)
			(layer "F.Fab")
			(effects
				(font
					(size 1.27 1.27)
				)
			)
		)
		(duplicate_pad_numbers_are_jumpers no)
		(fp_poly
			(pts
				(xy -0.4953 -0.2032) (xy 0.4953 -0.2032) (xy 0.4953 1.6002) (xy -0.4953 1.6002)
			)
			(stroke
				(width 0)
				(type default)
			)
			(fill no)
			(layer "F.CrtYd")
		)
		(fp_line
			(start -0.4953 1.6002)
			(end -0.4953 -0.2032)
			(stroke
				(width 0.1)
				(type default)
			)
			(layer "F.Fab")
		)
		(fp_line
			(start 0.4953 1.6002)
			(end -0.4953 1.6002)
			(stroke
				(width 0.1)
				(type default)
			)
			(layer "F.Fab")
		)
		(fp_line
			(start -0.4953 -0.2032)
			(end 0.4953 -0.2032)
			(stroke
				(width 0.1)
				(type default)
			)
			(layer "F.Fab")
		)
		(fp_line
			(start 0.4953 -0.2032)
			(end 0.4953 1.6002)
			(stroke
				(width 0.1)
				(type default)
			)
			(layer "F.Fab")
		)
		(pad "1" smd rect
			(at 0 0 270)
			(size 0.762 0.889)
			(layers "F.Cu" "F.Mask" "F.Paste")
			(net "PVDDQ_ABC")
		)
		(pad "2" smd rect
			(at 0 1.397 270)
			(size 0.762 0.889)
			(layers "F.Cu" "F.Mask" "F.Paste")
			(net "GND")
		)
		(zone
			(layer "F.Cu")
			(hatch none 0.5)
			(connect_pads
				(clearance 0)
			)
			(min_thickness 0.25)
			(keepout
				(tracks not_allowed)
				(vias allowed)
				(pads allowed)
				(copperpour not_allowed)
				(footprints allowed)
			)
			(placement
				(enabled no)
				(sheetname "")
			)
			(fill
				(thermal_gap 0.5)
				(thermal_bridge_width 0.5)
				(island_removal_mode 0)
			)
			(polygon
				(pts
					(xy 264.009124 -70.266814) (xy 264.009124 -69.504814) (xy 263.501124 -69.504814) (xy 263.501124 -70.266814)
				)
			)
		)
	)
	(footprint ""
		(layer "F.Cu")
		(at 401.8915 -37.9984 90)
		(property "Reference" "R1L7"
			(at 0 0 90)
			(layer "F.SilkS")
			(hide yes)
			(effects
				(font
					(size 1.27 1.27)
				)
			)
		)
		(property "Value" ""
			(at 0 0 90)
			(layer "F.Fab")
			(effects
				(font
					(size 1.27 1.27)
				)
			)
		)
		(duplicate_pad_numbers_are_jumpers no)
		(fp_poly
			(pts
				(xy -0.2794 -0.1016) (xy 0.2794 -0.1016) (xy 0.2794 0.9906) (xy -0.2794 0.9906)
			)
			(stroke
				(width 0)
				(type default)
			)
			(fill no)
			(layer "F.CrtYd")
		)
		(fp_line
			(start 0.2794 -0.1016)
			(end -0.2794 -0.1016)
			(stroke
				(width 0.1)
				(type default)
			)
			(layer "F.Fab")
		)
		(fp_line
			(start -0.2794 -0.1016)
			(end -0.2794 0.9906)
			(stroke
				(width 0.1)
				(type default)
			)
			(layer "F.Fab")
		)
		(fp_line
			(start 0.2794 0.9906)
			(end 0.2794 -0.1016)
			(stroke
				(width 0.1)
				(type default)
			)
			(layer "F.Fab")
		)
		(fp_line
			(start -0.2794 0.9906)
			(end 0.2794 0.9906)
			(stroke
				(width 0.1)
				(type default)
			)
			(layer "F.Fab")
		)
		(pad "1" smd rect
			(at 0 0 90)
			(size 0.508 0.508)
			(layers "F.Cu" "F.Mask" "F.Paste")
			(net "P3V3_STBY")
		)
		(pad "2" smd rect
			(at 0 0.889 90)
			(size 0.508 0.508)
			(layers "F.Cu" "F.Mask" "F.Paste")
			(net "FM_BMC_CPLD_MP_RST_N")
		)
		(zone
			(layer "F.Cu")
			(hatch none 0.5)
			(connect_pads
				(clearance 0)
			)
			(min_thickness 0.25)
			(keepout
				(tracks allowed)
				(vias not_allowed)
				(pads allowed)
				(copperpour not_allowed)
				(footprints allowed)
			)
			(placement
				(enabled no)
				(sheetname "")
			)
			(fill
				(thermal_gap 0.5)
				(thermal_bridge_width 0.5)
				(island_removal_mode 0)
			)
			(polygon
				(pts
					(xy 402.1455 -37.7444) (xy 402.1455 -38.2524) (xy 402.5265 -38.2524) (xy 402.5265 -37.7444)
				)
			)
		)
		(zone
			(layer "F.Cu")
			(hatch none 0.5)
			(connect_pads
				(clearance 0)
			)
			(min_thickness 0.25)
			(keepout
				(tracks not_allowed)
				(vias allowed)
				(pads allowed)
				(copperpour not_allowed)
				(footprints allowed)
			)
			(placement
				(enabled no)
				(sheetname "")
			)
			(fill
				(thermal_gap 0.5)
				(thermal_bridge_width 0.5)
				(island_removal_mode 0)
			)
			(polygon
				(pts
					(xy 402.5265 -37.7444) (xy 402.5265 -38.2524) (xy 402.1455 -38.2524) (xy 402.1455 -37.7444)
				)
			)
		)
	)
	(footprint ""
		(layer "F.Cu")
		(at 365.5568 -134.8994 180)
		(property "Reference" "R7A9"
			(at -0.8382 -0.67818 180)
			(unlocked yes)
			(layer "F.SilkS")
			(effects
				(font
					(size 0.4064 0.254)
					(thickness 0.1524)
				)
				(justify left)
			)
		)
		(property "Value" ""
			(at 0 0 180)
			(layer "F.Fab")
			(effects
				(font
					(size 1.27 1.27)
				)
			)
		)
		(duplicate_pad_numbers_are_jumpers no)
		(fp_poly
			(pts
				(xy -0.2794 -0.1016) (xy 0.2794 -0.1016) (xy 0.2794 0.9906) (xy -0.2794 0.9906)
			)
			(stroke
				(width 0)
				(type default)
			)
			(fill no)
			(layer "F.CrtYd")
		)
		(fp_line
			(start 0.2794 0.9906)
			(end 0.2794 -0.1016)
			(stroke
				(width 0.1)
				(type default)
			)
			(layer "F.Fab")
		)
		(fp_line
			(start 0.2794 -0.1016)
			(end -0.2794 -0.1016)
			(stroke
				(width 0.1)
				(type default)
			)
			(layer "F.Fab")
		)
		(fp_line
			(start -0.2794 0.9906)
			(end 0.2794 0.9906)
			(stroke
				(width 0.1)
				(type default)
			)
			(layer "F.Fab")
		)
		(fp_line
			(start -0.2794 -0.1016)
			(end -0.2794 0.9906)
			(stroke
				(width 0.1)
				(type default)
			)
			(layer "F.Fab")
		)
		(pad "1" smd rect
			(at 0 0 180)
			(size 0.508 0.508)
			(layers "F.Cu" "F.Mask" "F.Paste")
			(net "P3V3_STBY")
		)
		(pad "2" smd rect
			(at 0 0.889 180)
			(size 0.508 0.508)
			(layers "F.Cu" "F.Mask" "F.Paste")
			(net "PWRGD_PVDDQ_DEF")
		)
		(zone
			(layer "F.Cu")
			(hatch none 0.5)
			(connect_pads
				(clearance 0)
			)
			(min_thickness 0.25)
			(keepout
				(tracks not_allowed)
				(vias allowed)
				(pads allowed)
				(copperpour not_allowed)
				(footprints allowed)
			)
			(placement
				(enabled no)
				(sheetname "")
			)
			(fill
				(thermal_gap 0.5)
				(thermal_bridge_width 0.5)
				(island_removal_mode 0)
			)
			(polygon
				(pts
					(xy 365.8108 -135.5344) (xy 365.3028 -135.5344) (xy 365.3028 -135.1534) (xy 365.8108 -135.1534)
				)
			)
		)
		(zone
			(layer "F.Cu")
			(hatch none 0.5)
			(connect_pads
				(clearance 0)
			)
			(min_thickness 0.25)
			(keepout
				(tracks allowed)
				(vias not_allowed)
				(pads allowed)
				(copperpour not_allowed)
				(footprints allowed)
			)
			(placement
				(enabled no)
				(sheetname "")
			)
			(fill
				(thermal_gap 0.5)
				(thermal_bridge_width 0.5)
				(island_removal_mode 0)
			)
			(polygon
				(pts
					(xy 365.8108 -135.1534) (xy 365.3028 -135.1534) (xy 365.3028 -135.5344) (xy 365.8108 -135.5344)
				)
			)
		)
	)
)
